# BASEBOARD_FAB2 (Tioga Pass) — schematic netlist excerpt (pin names and nets, part order shuffled) for the footprints in the layout excerpt that follows; sources: Cadence DE-HDL packaged netlist, KiCad conversion of Wiwynn_Tioga_Pass_MB.brd

R7D9  RES  2.26K 1.0% CHIP  pkg 0402  page 181 : A = P3V3_STBY ; B = FM_MB_SLOT_ID1
C4A7  CAP  4.7UF 6.3V 10% X6S  pkg 0603  page 230 : A = VSENSE_PVDDQ_KLM_VTT ; B = GND

(kicad_pcb
	(version 20260206)
	(generator "pcbnew")
	(generator_version "10.0")
	(general
		(thickness 1.6)
		(legacy_teardrops no)
	)
	(paper "A4")
	(title_block
		(title "Wiwynn_Tioga_Pass_MB.brd")
		(comment 1 "Tioga Pass / footprints 2006-2007 of 4770")
	)
	(layers
		(0 "F.Cu" signal "TOP")
		(4 "In1.Cu" signal "L2GND")
		(6 "In2.Cu" signal "L3")
		(8 "In3.Cu" signal "L4GND")
		(10 "In4.Cu" signal "L5")
		(12 "In5.Cu" signal "L6GND")
		(14 "In6.Cu" signal "L7VCC")
		(16 "In7.Cu" signal "L8VCC")
		(18 "In8.Cu" signal "L9GND")
		(20 "In9.Cu" signal "L10")
		(22 "In10.Cu" signal "L11GND")
		(24 "In11.Cu" signal "L12")
		(26 "In12.Cu" signal "L13GND")
		(2 "B.Cu" signal "BOTTOM")
		(9 "F.Adhes" user "F.Adhesive")
		(11 "B.Adhes" user "B.Adhesive")
		(13 "F.Paste" user "Package Geometry/Pastemask Top")
		(15 "B.Paste" user "Package Geometry/Pastemask Bottom")
		(5 "F.SilkS" user "Ref Des/Silkscreen Top")
		(7 "B.SilkS" user "Ref Des/Silkscreen Bottom")
		(1 "F.Mask" user "Board Geometry/Soldermask Top")
		(3 "B.Mask" user "Board Geometry/Soldermask Bottom")
		(17 "Dwgs.User" user "User.Drawings")
		(19 "Cmts.User" user "User.Comments")
		(21 "Eco1.User" user "User.Eco1")
		(23 "Eco2.User" user "User.Eco2")
		(25 "Edge.Cuts" user "Board Geometry/Outline")
		(27 "Margin" user)
		(31 "F.CrtYd" user "Package Geometry/Place Bound Top")
		(29 "B.CrtYd" user "Package Geometry/Place Bound Bottom")
		(35 "F.Fab" user "Ref Des/Assembly Top")
		(33 "B.Fab" user "Ref Des/Assembly Bottom")
	)
	(footprint ""
		(layer "F.Cu")
		(at 383.794 -87.3125 180)
		(property "Reference" "R7D9"
			(at 0 0 180)
			(layer "F.SilkS")
			(hide yes)
			(effects
				(font
					(size 1.27 1.27)
				)
			)
		)
		(property "Value" ""
			(at 0 0 180)
			(layer "F.Fab")
			(effects
				(font
					(size 1.27 1.27)
				)
			)
		)
		(duplicate_pad_numbers_are_jumpers no)
		(fp_poly
			(pts
				(xy -0.2794 -0.1016) (xy 0.2794 -0.1016) (xy 0.2794 0.9906) (xy -0.2794 0.9906)
			)
			(stroke
				(width 0)
				(type default)
			)
			(fill no)
			(layer "F.CrtYd")
		)
		(fp_line
			(start 0.2794 0.9906)
			(end 0.2794 -0.1016)
			(stroke
				(width 0.1)
				(type default)
			)
			(layer "F.Fab")
		)
		(fp_line
			(start 0.2794 -0.1016)
			(end -0.2794 -0.1016)
			(stroke
				(width 0.1)
				(type default)
			)
			(layer "F.Fab")
		)
		(fp_line
			(start -0.2794 0.9906)
			(end 0.2794 0.9906)
			(stroke
				(width 0.1)
				(type default)
			)
			(layer "F.Fab")
		)
		(fp_line
			(start -0.2794 -0.1016)
			(end -0.2794 0.9906)
			(stroke
				(width 0.1)
				(type default)
			)
			(layer "F.Fab")
		)
		(pad "1" smd rect
			(at 0 0 180)
			(size 0.508 0.508)
			(layers "F.Cu" "F.Mask" "F.Paste")
			(net "P3V3_STBY")
		)
		(pad "2" smd rect
			(at 0 0.889 180)
			(size 0.508 0.508)
			(layers "F.Cu" "F.Mask" "F.Paste")
			(net "FM_MB_SLOT_ID1")
		)
		(zone
			(layer "F.Cu")
			(hatch none 0.5)
			(connect_pads
				(clearance 0)
			)
			(min_thickness 0.25)
			(keepout
				(tracks not_allowed)
				(vias allowed)
				(pads allowed)
				(copperpour not_allowed)
				(footprints allowed)
			)
			(placement
				(enabled no)
				(sheetname "")
			)
			(fill
				(thermal_gap 0.5)
				(thermal_bridge_width 0.5)
				(island_removal_mode 0)
			)
			(polygon
				(pts
					(xy 384.048 -87.9475) (xy 383.54 -87.9475) (xy 383.54 -87.5665) (xy 384.048 -87.5665)
				)
			)
		)
		(zone
			(layer "F.Cu")
			(hatch none 0.5)
			(connect_pads
				(clearance 0)
			)
			(min_thickness 0.25)
			(keepout
				(tracks allowed)
				(vias not_allowed)
				(pads allowed)
				(copperpour not_allowed)
				(footprints allowed)
			)
			(placement
				(enabled no)
				(sheetname "")
			)
			(fill
				(thermal_gap 0.5)
				(thermal_bridge_width 0.5)
				(island_removal_mode 0)
			)
			(polygon
				(pts
					(xy 384.048 -87.5665) (xy 383.54 -87.5665) (xy 383.54 -87.9475) (xy 384.048 -87.9475)
				)
			)
		)
	)
	(footprint ""
		(layer "F.Cu")
		(at 173.78172 -147.95246 90)
		(property "Reference" "C4A7"
			(at 0 0 90)
			(layer "F.SilkS")
			(hide yes)
			(effects
				(font
					(size 1.27 1.27)
				)
			)
		)
		(property "Value" ""
			(at 0 0 90)
			(layer "F.Fab")
			(effects
				(font
					(size 1.27 1.27)
				)
			)
		)
		(duplicate_pad_numbers_are_jumpers no)
		(fp_poly
			(pts
				(xy -0.4953 -0.2032) (xy 0.4953 -0.2032) (xy 0.4953 1.6002) (xy -0.4953 1.6002)
			)
			(stroke
				(width 0)
				(type default)
			)
			(fill no)
			(layer "F.CrtYd")
		)
		(fp_line
			(start 0.4953 -0.2032)
			(end 0.4953 1.6002)
			(stroke
				(width 0.1)
				(type default)
			)
			(layer "F.Fab")
		)
		(fp_line
			(start -0.4953 -0.2032)
			(end 0.4953 -0.2032)
			(stroke
				(width 0.1)
				(type default)
			)
			(layer "F.Fab")
		)
		(fp_line
			(start 0.4953 1.6002)
			(end -0.4953 1.6002)
			(stroke
				(width 0.1)
				(type default)
			)
			(layer "F.Fab")
		)
		(fp_line
			(start -0.4953 1.6002)
			(end -0.4953 -0.2032)
			(stroke
				(width 0.1)
				(type default)
			)
			(layer "F.Fab")
		)
		(pad "1" smd rect
			(at 0 0 90)
			(size 0.762 0.889)
			(layers "F.Cu" "F.Mask" "F.Paste")
			(net "VSENSE_PVDDQ_KLM_VTT")
		)
		(pad "2" smd rect
			(at 0 1.397 90)
			(size 0.762 0.889)
			(layers "F.Cu" "F.Mask" "F.Paste")
			(net "GND")
		)
		(zone
			(layer "F.Cu")
			(hatch none 0.5)
			(connect_pads
				(clearance 0)
			)
			(min_thickness 0.25)
			(keepout
				(tracks not_allowed)
				(vias allowed)
				(pads allowed)
				(copperpour not_allowed)
				(footprints allowed)
			)
			(placement
				(enabled no)
				(sheetname "")
			)
			(fill
				(thermal_gap 0.5)
				(thermal_bridge_width 0.5)
				(island_removal_mode 0)
			)
			(polygon
				(pts
					(xy 174.22622 -147.57146) (xy 174.22622 -148.33346) (xy 174.73422 -148.33346) (xy 174.73422 -147.57146)
				)
			)
		)
	)
)
